(kicad_pcb
	(version 20260206)
	(generator "pcbnew")
	(generator_version "10.0")
	(general
		(thickness 1.6)
		(legacy_teardrops no)
	)
	(paper "A4")
	(title_block
		(title "01162023_DA0F0TEBIF0_F0T_Expander_BD_F_brd_V02_OCP.brd")
		(comment 1 "Grand Teton / footprints 53-58 of 9728")
	)
	(layers
		(0 "F.Cu" signal "TOP")
		(4 "In1.Cu" signal "GND")
		(6 "In2.Cu" signal "VCC")
		(8 "In3.Cu" signal "VCC1")
		(10 "In4.Cu" signal "GND1")
		(12 "In5.Cu" signal "IN1")
		(14 "In6.Cu" signal "GND2")
		(16 "In7.Cu" signal "IN2")
		(18 "In8.Cu" signal "GND3")
		(20 "In9.Cu" signal "IN3")
		(22 "In10.Cu" signal "GND4")
		(24 "In11.Cu" signal "IN4")
		(26 "In12.Cu" signal "GND5")
		(28 "In13.Cu" signal "IN5")
		(30 "In14.Cu" signal "GND6")
		(32 "In15.Cu" signal "IN6")
		(34 "In16.Cu" signal "GND7")
		(2 "B.Cu" signal "BOTTOM")
		(9 "F.Adhes" user "F.Adhesive")
		(11 "B.Adhes" user "B.Adhesive")
		(13 "F.Paste" user "Package Geometry/Pastemask Top")
		(15 "B.Paste" user "Package Geometry/Pastemask Bottom")
		(5 "F.SilkS" user "Ref Des/Silkscreen Top")
		(7 "B.SilkS" user "Ref Des/Silkscreen Bottom")
		(1 "F.Mask" user "Board Geometry/Soldermask Top")
		(3 "B.Mask" user "Board Geometry/Soldermask Bottom")
		(17 "Dwgs.User" user "User.Drawings")
		(19 "Cmts.User" user "User.Comments")
		(21 "Eco1.User" user "User.Eco1")
		(23 "Eco2.User" user "User.Eco2")
		(25 "Edge.Cuts" user "Board Geometry/Outline")
		(27 "Margin" user)
		(31 "F.CrtYd" user "Package Geometry/Place Bound Top")
		(29 "B.CrtYd" user "Package Geometry/Place Bound Bottom")
		(35 "F.Fab" user "Ref Des/Assembly Top")
		(33 "B.Fab" user "Ref Des/Assembly Bottom")
	)
	(footprint ""
		(layer "F.Cu")
		(at 352.17227 -32.848042 90)
		(property "Reference" "PC961"
			(at 0 0 90)
			(layer "F.SilkS")
			(hide yes)
			(effects
				(font
					(size 1.27 1.27)
				)
			)
		)
		(property "Value" ""
			(at 0 0 90)
			(layer "F.Fab")
			(effects
				(font
					(size 1.27 1.27)
				)
			)
		)
		(duplicate_pad_numbers_are_jumpers no)
		(fp_line
			(start 0.7874 -0.4064)
			(end 0.7874 0.4064)
			(stroke
				(width 0.1524)
				(type default)
			)
			(layer "F.SilkS")
		)
		(fp_line
			(start -0.7874 -0.4064)
			(end 0.7874 -0.4064)
			(stroke
				(width 0.1524)
				(type default)
			)
			(layer "F.SilkS")
		)
		(fp_line
			(start 0.7874 0.4064)
			(end -0.7874 0.4064)
			(stroke
				(width 0.1524)
				(type default)
			)
			(layer "F.SilkS")
		)
		(fp_line
			(start -0.7874 0.4064)
			(end -0.7874 -0.4064)
			(stroke
				(width 0.1524)
				(type default)
			)
			(layer "F.SilkS")
		)
		(fp_line
			(start -0.12065 -0.305054)
			(end -0.12065 -0.2794)
			(stroke
				(width 0.1)
				(type default)
			)
			(layer "F.Fab")
		)
		(fp_line
			(start -0.67945 -0.305054)
			(end -0.12065 -0.305054)
			(stroke
				(width 0.1)
				(type default)
			)
			(layer "F.Fab")
		)
		(fp_line
			(start 0.67945 -0.3048)
			(end 0.67945 0.3048)
			(stroke
				(width 0.1)
				(type default)
			)
			(layer "F.Fab")
		)
		(fp_line
			(start 0.12065 -0.3048)
			(end 0.67945 -0.3048)
			(stroke
				(width 0.1)
				(type default)
			)
			(layer "F.Fab")
		)
		(fp_line
			(start 0.12065 -0.2794)
			(end 0.12065 -0.3048)
			(stroke
				(width 0.1)
				(type default)
			)
			(layer "F.Fab")
		)
		(fp_line
			(start -0.12065 -0.2794)
			(end 0.12065 -0.2794)
			(stroke
				(width 0.1)
				(type default)
			)
			(layer "F.Fab")
		)
		(fp_line
			(start 0.120396 0.2794)
			(end -0.12065 0.2794)
			(stroke
				(width 0.1)
				(type default)
			)
			(layer "F.Fab")
		)
		(fp_line
			(start -0.12065 0.2794)
			(end -0.12065 0.3048)
			(stroke
				(width 0.1)
				(type default)
			)
			(layer "F.Fab")
		)
		(fp_line
			(start 0.67945 0.3048)
			(end 0.120396 0.3048)
			(stroke
				(width 0.1)
				(type default)
			)
			(layer "F.Fab")
		)
		(fp_line
			(start 0.120396 0.3048)
			(end 0.120396 0.2794)
			(stroke
				(width 0.1)
				(type default)
			)
			(layer "F.Fab")
		)
		(fp_line
			(start -0.12065 0.3048)
			(end -0.67945 0.3048)
			(stroke
				(width 0.1)
				(type default)
			)
			(layer "F.Fab")
		)
		(fp_line
			(start -0.67945 0.3048)
			(end -0.67945 -0.305054)
			(stroke
				(width 0.1)
				(type default)
			)
			(layer "F.Fab")
		)
		(pad "1" smd circle
			(at -0.40005 0 90)
			(size 0 0)
			(layers "F.Cu" "F.Mask" "F.Paste")
			(net "P3V3_SSD12_CO_GATE")
		)
		(pad "2" smd circle
			(at 0.40005 0 90)
			(size 0 0)
			(layers "F.Cu" "F.Mask" "F.Paste")
			(net "GND")
		)
	)
	(footprint ""
		(layer "F.Cu")
		(at 329.692 -234.061 -90)
		(property "Reference" "R1781"
			(at 0 0 270)
			(layer "F.SilkS")
			(hide yes)
			(effects
				(font
					(size 1.27 1.27)
				)
			)
		)
		(property "Value" ""
			(at 0 0 270)
			(layer "F.Fab")
			(effects
				(font
					(size 1.27 1.27)
				)
			)
		)
		(duplicate_pad_numbers_are_jumpers no)
		(fp_line
			(start -0.7874 0.4064)
			(end -0.7874 -0.4064)
			(stroke
				(width 0.1524)
				(type default)
			)
			(layer "F.SilkS")
		)
		(fp_line
			(start 0.7874 0.4064)
			(end -0.7874 0.4064)
			(stroke
				(width 0.1524)
				(type default)
			)
			(layer "F.SilkS")
		)
		(fp_line
			(start -0.7874 -0.4064)
			(end 0.7874 -0.4064)
			(stroke
				(width 0.1524)
				(type default)
			)
			(layer "F.SilkS")
		)
		(fp_line
			(start 0.7874 -0.4064)
			(end 0.7874 0.4064)
			(stroke
				(width 0.1524)
				(type default)
			)
			(layer "F.SilkS")
		)
		(fp_line
			(start -0.67945 0.3048)
			(end -0.67945 -0.305054)
			(stroke
				(width 0.1)
				(type default)
			)
			(layer "F.Fab")
		)
		(fp_line
			(start -0.12065 0.3048)
			(end -0.67945 0.3048)
			(stroke
				(width 0.1)
				(type default)
			)
			(layer "F.Fab")
		)
		(fp_line
			(start 0.120396 0.3048)
			(end 0.120396 0.2794)
			(stroke
				(width 0.1)
				(type default)
			)
			(layer "F.Fab")
		)
		(fp_line
			(start 0.67945 0.3048)
			(end 0.120396 0.3048)
			(stroke
				(width 0.1)
				(type default)
			)
			(layer "F.Fab")
		)
		(fp_line
			(start -0.12065 0.2794)
			(end -0.12065 0.3048)
			(stroke
				(width 0.1)
				(type default)
			)
			(layer "F.Fab")
		)
		(fp_line
			(start 0.120396 0.2794)
			(end -0.12065 0.2794)
			(stroke
				(width 0.1)
				(type default)
			)
			(layer "F.Fab")
		)
		(fp_line
			(start -0.12065 -0.2794)
			(end 0.12065 -0.2794)
			(stroke
				(width 0.1)
				(type default)
			)
			(layer "F.Fab")
		)
		(fp_line
			(start 0.12065 -0.2794)
			(end 0.12065 -0.3048)
			(stroke
				(width 0.1)
				(type default)
			)
			(layer "F.Fab")
		)
		(fp_line
			(start 0.12065 -0.3048)
			(end 0.67945 -0.3048)
			(stroke
				(width 0.1)
				(type default)
			)
			(layer "F.Fab")
		)
		(fp_line
			(start 0.67945 -0.3048)
			(end 0.67945 0.3048)
			(stroke
				(width 0.1)
				(type default)
			)
			(layer "F.Fab")
		)
		(fp_line
			(start -0.67945 -0.305054)
			(end -0.12065 -0.305054)
			(stroke
				(width 0.1)
				(type default)
			)
			(layer "F.Fab")
		)
		(fp_line
			(start -0.12065 -0.305054)
			(end -0.12065 -0.2794)
			(stroke
				(width 0.1)
				(type default)
			)
			(layer "F.Fab")
		)
		(pad "1" smd circle
			(at -0.40005 0 270)
			(size 0 0)
			(layers "F.Cu" "F.Mask" "F.Paste")
			(net "PRSNT_GPU_ISO_N")
		)
		(pad "2" smd circle
			(at 0.40005 0 270)
			(size 0 0)
			(layers "F.Cu" "F.Mask" "F.Paste")
			(net "P3V3_AUX")
		)
	)
	(footprint ""
		(layer "F.Cu")
		(at 227.736654 -310.568848)
		(property "Reference" "R844"
			(at 0 0 0)
			(layer "F.SilkS")
			(hide yes)
			(effects
				(font
					(size 1.27 1.27)
				)
			)
		)
		(property "Value" ""
			(at 0 0 0)
			(layer "F.Fab")
			(effects
				(font
					(size 1.27 1.27)
				)
			)
		)
		(duplicate_pad_numbers_are_jumpers no)
		(fp_line
			(start -0.7874 -0.4064)
			(end 0.7874 -0.4064)
			(stroke
				(width 0.1524)
				(type default)
			)
			(layer "F.SilkS")
		)
		(fp_line
			(start -0.7874 0.4064)
			(end -0.7874 -0.4064)
			(stroke
				(width 0.1524)
				(type default)
			)
			(layer "F.SilkS")
		)
		(fp_line
			(start 0.7874 -0.4064)
			(end 0.7874 0.4064)
			(stroke
				(width 0.1524)
				(type default)
			)
			(layer "F.SilkS")
		)
		(fp_line
			(start 0.7874 0.4064)
			(end -0.7874 0.4064)
			(stroke
				(width 0.1524)
				(type default)
			)
			(layer "F.SilkS")
		)
		(fp_line
			(start -0.67945 -0.305054)
			(end -0.12065 -0.305054)
			(stroke
				(width 0.1)
				(type default)
			)
			(layer "F.Fab")
		)
		(fp_line
			(start -0.67945 0.3048)
			(end -0.67945 -0.305054)
			(stroke
				(width 0.1)
				(type default)
			)
			(layer "F.Fab")
		)
		(fp_line
			(start -0.12065 -0.305054)
			(end -0.12065 -0.2794)
			(stroke
				(width 0.1)
				(type default)
			)
			(layer "F.Fab")
		)
		(fp_line
			(start -0.12065 -0.2794)
			(end 0.12065 -0.2794)
			(stroke
				(width 0.1)
				(type default)
			)
			(layer "F.Fab")
		)
		(fp_line
			(start -0.12065 0.2794)
			(end -0.12065 0.3048)
			(stroke
				(width 0.1)
				(type default)
			)
			(layer "F.Fab")
		)
		(fp_line
			(start -0.12065 0.3048)
			(end -0.67945 0.3048)
			(stroke
				(width 0.1)
				(type default)
			)
			(layer "F.Fab")
		)
		(fp_line
			(start 0.120396 0.2794)
			(end -0.12065 0.2794)
			(stroke
				(width 0.1)
				(type default)
			)
			(layer "F.Fab")
		)
		(fp_line
			(start 0.120396 0.3048)
			(end 0.120396 0.2794)
			(stroke
				(width 0.1)
				(type default)
			)
			(layer "F.Fab")
		)
		(fp_line
			(start 0.12065 -0.3048)
			(end 0.67945 -0.3048)
			(stroke
				(width 0.1)
				(type default)
			)
			(layer "F.Fab")
		)
		(fp_line
			(start 0.12065 -0.2794)
			(end 0.12065 -0.3048)
			(stroke
				(width 0.1)
				(type default)
			)
			(layer "F.Fab")
		)
		(fp_line
			(start 0.67945 -0.3048)
			(end 0.67945 0.3048)
			(stroke
				(width 0.1)
				(type default)
			)
			(layer "F.Fab")
		)
		(fp_line
			(start 0.67945 0.3048)
			(end 0.120396 0.3048)
			(stroke
				(width 0.1)
				(type default)
			)
			(layer "F.Fab")
		)
		(pad "1" smd circle
			(at -0.40005 0)
			(size 0 0)
			(layers "F.Cu" "F.Mask" "F.Paste")
			(net "P1V25_PEX1_EN")
		)
		(pad "2" smd circle
			(at 0.40005 0)
			(size 0 0)
			(layers "F.Cu" "F.Mask" "F.Paste")
			(net "PWR_EN_PEX_R")
		)
	)
	(footprint ""
		(layer "F.Cu")
		(at 221.990158 -77.563472)
		(property "Reference" "R4268"
			(at 0 0 0)
			(layer "F.SilkS")
			(hide yes)
			(effects
				(font
					(size 1.27 1.27)
				)
			)
		)
		(property "Value" ""
			(at 0 0 0)
			(layer "F.Fab")
			(effects
				(font
					(size 1.27 1.27)
				)
			)
		)
		(duplicate_pad_numbers_are_jumpers no)
		(fp_line
			(start -0.7874 -0.4064)
			(end 0.7874 -0.4064)
			(stroke
				(width 0.1524)
				(type default)
			)
			(layer "F.SilkS")
		)
		(fp_line
			(start -0.7874 0.4064)
			(end -0.7874 -0.4064)
			(stroke
				(width 0.1524)
				(type default)
			)
			(layer "F.SilkS")
		)
		(fp_line
			(start 0.7874 -0.4064)
			(end 0.7874 0.4064)
			(stroke
				(width 0.1524)
				(type default)
			)
			(layer "F.SilkS")
		)
		(fp_line
			(start 0.7874 0.4064)
			(end -0.7874 0.4064)
			(stroke
				(width 0.1524)
				(type default)
			)
			(layer "F.SilkS")
		)
		(fp_line
			(start -0.67945 -0.305054)
			(end -0.12065 -0.305054)
			(stroke
				(width 0.1)
				(type default)
			)
			(layer "F.Fab")
		)
		(fp_line
			(start -0.67945 0.3048)
			(end -0.67945 -0.305054)
			(stroke
				(width 0.1)
				(type default)
			)
			(layer "F.Fab")
		)
		(fp_line
			(start -0.12065 -0.305054)
			(end -0.12065 -0.2794)
			(stroke
				(width 0.1)
				(type default)
			)
			(layer "F.Fab")
		)
		(fp_line
			(start -0.12065 -0.2794)
			(end 0.12065 -0.2794)
			(stroke
				(width 0.1)
				(type default)
			)
			(layer "F.Fab")
		)
		(fp_line
			(start -0.12065 0.2794)
			(end -0.12065 0.3048)
			(stroke
				(width 0.1)
				(type default)
			)
			(layer "F.Fab")
		)
		(fp_line
			(start -0.12065 0.3048)
			(end -0.67945 0.3048)
			(stroke
				(width 0.1)
				(type default)
			)
			(layer "F.Fab")
		)
		(fp_line
			(start 0.120396 0.2794)
			(end -0.12065 0.2794)
			(stroke
				(width 0.1)
				(type default)
			)
			(layer "F.Fab")
		)
		(fp_line
			(start 0.120396 0.3048)
			(end 0.120396 0.2794)
			(stroke
				(width 0.1)
				(type default)
			)
			(layer "F.Fab")
		)
		(fp_line
			(start 0.12065 -0.3048)
			(end 0.67945 -0.3048)
			(stroke
				(width 0.1)
				(type default)
			)
			(layer "F.Fab")
		)
		(fp_line
			(start 0.12065 -0.2794)
			(end 0.12065 -0.3048)
			(stroke
				(width 0.1)
				(type default)
			)
			(layer "F.Fab")
		)
		(fp_line
			(start 0.67945 -0.3048)
			(end 0.67945 0.3048)
			(stroke
				(width 0.1)
				(type default)
			)
			(layer "F.Fab")
		)
		(fp_line
			(start 0.67945 0.3048)
			(end 0.120396 0.3048)
			(stroke
				(width 0.1)
				(type default)
			)
			(layer "F.Fab")
		)
		(pad "1" smd circle
			(at -0.40005 0)
			(size 0 0)
			(layers "F.Cu" "F.Mask" "F.Paste")
			(net "SSD8_LED")
		)
		(pad "2" smd circle
			(at 0.40005 0)
			(size 0 0)
			(layers "F.Cu" "F.Mask" "F.Paste")
			(net "SSD8_LED_R")
		)
	)
	(footprint ""
		(layer "F.Cu")
		(at 336.042 -176.911)
		(property "Reference" "R4731"
			(at 0 0 0)
			(layer "F.SilkS")
			(hide yes)
			(effects
				(font
					(size 1.27 1.27)
				)
			)
		)
		(property "Value" ""
			(at 0 0 0)
			(layer "F.Fab")
			(effects
				(font
					(size 1.27 1.27)
				)
			)
		)
		(duplicate_pad_numbers_are_jumpers no)
		(fp_line
			(start -0.7874 -0.4064)
			(end 0.7874 -0.4064)
			(stroke
				(width 0.1524)
				(type default)
			)
			(layer "F.SilkS")
		)
		(fp_line
			(start -0.7874 0.4064)
			(end -0.7874 -0.4064)
			(stroke
				(width 0.1524)
				(type default)
			)
			(layer "F.SilkS")
		)
		(fp_line
			(start 0.7874 -0.4064)
			(end 0.7874 0.4064)
			(stroke
				(width 0.1524)
				(type default)
			)
			(layer "F.SilkS")
		)
		(fp_line
			(start 0.7874 0.4064)
			(end -0.7874 0.4064)
			(stroke
				(width 0.1524)
				(type default)
			)
			(layer "F.SilkS")
		)
		(fp_line
			(start -0.67945 -0.305054)
			(end -0.12065 -0.305054)
			(stroke
				(width 0.1)
				(type default)
			)
			(layer "F.Fab")
		)
		(fp_line
			(start -0.67945 0.3048)
			(end -0.67945 -0.305054)
			(stroke
				(width 0.1)
				(type default)
			)
			(layer "F.Fab")
		)
		(fp_line
			(start -0.12065 -0.305054)
			(end -0.12065 -0.2794)
			(stroke
				(width 0.1)
				(type default)
			)
			(layer "F.Fab")
		)
		(fp_line
			(start -0.12065 -0.2794)
			(end 0.12065 -0.2794)
			(stroke
				(width 0.1)
				(type default)
			)
			(layer "F.Fab")
		)
		(fp_line
			(start -0.12065 0.2794)
			(end -0.12065 0.3048)
			(stroke
				(width 0.1)
				(type default)
			)
			(layer "F.Fab")
		)
		(fp_line
			(start -0.12065 0.3048)
			(end -0.67945 0.3048)
			(stroke
				(width 0.1)
				(type default)
			)
			(layer "F.Fab")
		)
		(fp_line
			(start 0.120396 0.2794)
			(end -0.12065 0.2794)
			(stroke
				(width 0.1)
				(type default)
			)
			(layer "F.Fab")
		)
		(fp_line
			(start 0.120396 0.3048)
			(end 0.120396 0.2794)
			(stroke
				(width 0.1)
				(type default)
			)
			(layer "F.Fab")
		)
		(fp_line
			(start 0.12065 -0.3048)
			(end 0.67945 -0.3048)
			(stroke
				(width 0.1)
				(type default)
			)
			(layer "F.Fab")
		)
		(fp_line
			(start 0.12065 -0.2794)
			(end 0.12065 -0.3048)
			(stroke
				(width 0.1)
				(type default)
			)
			(layer "F.Fab")
		)
		(fp_line
			(start 0.67945 -0.3048)
			(end 0.67945 0.3048)
			(stroke
				(width 0.1)
				(type default)
			)
			(layer "F.Fab")
		)
		(fp_line
			(start 0.67945 0.3048)
			(end 0.120396 0.3048)
			(stroke
				(width 0.1)
				(type default)
			)
			(layer "F.Fab")
		)
		(pad "1" smd circle
			(at -0.40005 0)
			(size 0 0)
			(layers "F.Cu" "F.Mask" "F.Paste")
			(net "P3V3_AUX")
		)
		(pad "2" smd circle
			(at 0.40005 0)
			(size 0 0)
			(layers "F.Cu" "F.Mask" "F.Paste")
			(net "RST_PEX_SSD9_PERST_R_N")
		)
	)
	(footprint ""
		(layer "F.Cu")
		(at 289.101784 -32.849312 90)
		(property "Reference" "R5694"
			(at 0 0 90)
			(layer "F.SilkS")
			(hide yes)
			(effects
				(font
					(size 1.27 1.27)
				)
			)
		)
		(property "Value" ""
			(at 0 0 90)
			(layer "F.Fab")
			(effects
				(font
					(size 1.27 1.27)
				)
			)
		)
		(duplicate_pad_numbers_are_jumpers no)
		(fp_line
			(start 0.7874 -0.4064)
			(end 0.7874 0.4064)
			(stroke
				(width 0.1524)
				(type default)
			)
			(layer "F.SilkS")
		)
		(fp_line
			(start -0.7874 -0.4064)
			(end 0.7874 -0.4064)
			(stroke
				(width 0.1524)
				(type default)
			)
			(layer "F.SilkS")
		)
		(fp_line
			(start 0.7874 0.4064)
			(end -0.7874 0.4064)
			(stroke
				(width 0.1524)
				(type default)
			)
			(layer "F.SilkS")
		)
		(fp_line
			(start -0.7874 0.4064)
			(end -0.7874 -0.4064)
			(stroke
				(width 0.1524)
				(type default)
			)
			(layer "F.SilkS")
		)
		(fp_line
			(start -0.12065 -0.305054)
			(end -0.12065 -0.2794)
			(stroke
				(width 0.1)
				(type default)
			)
			(layer "F.Fab")
		)
		(fp_line
			(start -0.67945 -0.305054)
			(end -0.12065 -0.305054)
			(stroke
				(width 0.1)
				(type default)
			)
			(layer "F.Fab")
		)
		(fp_line
			(start 0.67945 -0.3048)
			(end 0.67945 0.3048)
			(stroke
				(width 0.1)
				(type default)
			)
			(layer "F.Fab")
		)
		(fp_line
			(start 0.12065 -0.3048)
			(end 0.67945 -0.3048)
			(stroke
				(width 0.1)
				(type default)
			)
			(layer "F.Fab")
		)
		(fp_line
			(start 0.12065 -0.2794)
			(end 0.12065 -0.3048)
			(stroke
				(width 0.1)
				(type default)
			)
			(layer "F.Fab")
		)
		(fp_line
			(start -0.12065 -0.2794)
			(end 0.12065 -0.2794)
			(stroke
				(width 0.1)
				(type default)
			)
			(layer "F.Fab")
		)
		(fp_line
			(start 0.120396 0.2794)
			(end -0.12065 0.2794)
			(stroke
				(width 0.1)
				(type default)
			)
			(layer "F.Fab")
		)
		(fp_line
			(start -0.12065 0.2794)
			(end -0.12065 0.3048)
			(stroke
				(width 0.1)
				(type default)
			)
			(layer "F.Fab")
		)
		(fp_line
			(start 0.67945 0.3048)
			(end 0.120396 0.3048)
			(stroke
				(width 0.1)
				(type default)
			)
			(layer "F.Fab")
		)
		(fp_line
			(start 0.120396 0.3048)
			(end 0.120396 0.2794)
			(stroke
				(width 0.1)
				(type default)
			)
			(layer "F.Fab")
		)
		(fp_line
			(start -0.12065 0.3048)
			(end -0.67945 0.3048)
			(stroke
				(width 0.1)
				(type default)
			)
			(layer "F.Fab")
		)
		(fp_line
			(start -0.67945 0.3048)
			(end -0.67945 -0.305054)
			(stroke
				(width 0.1)
				(type default)
			)
			(layer "F.Fab")
		)
		(pad "1" smd circle
			(at -0.40005 0 90)
			(size 0 0)
			(layers "F.Cu" "F.Mask" "F.Paste")
			(net "RST_SMB_SSD10_ISO_R_N")
		)
		(pad "2" smd circle
			(at 0.40005 0 90)
			(size 0 0)
			(layers "F.Cu" "F.Mask" "F.Paste")
			(net "RST_SMB_SSD10_ISO_N")
		)
	)
)
